%FSTAX23Y23*%
%MOIN*%
%SFA1B1*%

%IPPOS*%
%ADD17C,0.006000*%
%ADD19C,0.008000*%
%ADD21C,0.005000*%
%ADD153C,0.020000*%
%ADD160C,0.075000*%
%ADD167C,0.055000*%
%ADD171C,0.016000*%
%LNgrandmaster-1*%
%LPD*%
G54D17*
X02083Y01411D02*
X02084Y01411D01*
X03407*
X03407Y01411*
G54D19*
X02626Y02716D02*
D01*
X02627Y02716*
X02627Y02716*
X02628Y02716*
X02628Y02716*
X02629Y02717*
X02629Y02717*
X0263Y02717*
X0263Y02717*
X02631Y02718*
X02631Y02718*
X02632Y02718*
X02632Y02718*
X02671Y02754D02*
D01*
X02671Y02754*
X0267Y02754*
X02669Y02754*
X02669Y02754*
X02668Y02754*
X02668Y02754*
X02667Y02753*
X02667Y02753*
X02666Y02753*
X02666Y02753*
X02666Y02752*
X02665Y02752*
X02396Y02718D02*
D01*
X02396Y02718*
X02397Y02718*
X02397Y02717*
X02398Y02717*
X02398Y02717*
X02399Y02717*
X02399Y02716*
X024Y02716*
X024Y02716*
X02401Y02716*
X02401Y02716*
X02401Y02716*
X02671Y02754D02*
X03089D01*
X02401Y02716D02*
X02626D01*
X02671Y02754D02*
X02671D01*
X02632Y02718D02*
X02665Y02752D01*
X02394Y0272D02*
X02396Y02718D01*
X02494Y02661D02*
X04114D01*
X0233Y02215D02*
X05577D01*
X01393Y01816D02*
X01517Y01941D01*
X02384*
X01399Y03522D02*
X014Y03523D01*
X01408Y03979D02*
Y0398D01*
X014Y03971D02*
X01408Y03979D01*
X014Y03523D02*
Y03971D01*
X01399Y03075D02*
Y03522D01*
X04605Y02997D02*
X04794Y02808D01*
X03276Y02964D02*
X03277Y02963D01*
X03276Y02964D02*
Y02983D01*
X03275Y02984D02*
X03276Y02983D01*
X03275Y02984D02*
Y03019D01*
X03331Y03075*
Y03153*
X03297Y03187D02*
X03331Y03153D01*
X0321Y03135D02*
X03262Y03187D01*
X03297*
X03183Y03135D02*
X0321D01*
X03232Y03187D02*
X0326Y03215D01*
X03468*
X03188Y03187D02*
X03232D01*
X01798Y01304D02*
X0181Y01316D01*
X02189Y01281D02*
X02206Y01298D01*
X01572Y01281D02*
X02189D01*
X01567Y01285D02*
X01572Y01281D01*
X0406Y03155D02*
D01*
X03854Y03151D02*
X03857D01*
X03861Y03155*
X0406*
X04012Y03115D02*
D01*
X03939Y03121D02*
X03942D01*
X03948Y03115*
X04012*
X06296D01*
X03277Y02963D02*
X03351Y02889D01*
X03369*
X0337Y02888*
X03232Y03098D02*
X03275Y03141D01*
X03089Y02754D02*
X03232Y02897D01*
Y03098*
X03097Y0297D02*
X03197D01*
X03096Y02969D02*
X03097Y0297D01*
X02577Y02969D02*
X03096D01*
X03653Y03293D02*
X03655Y03294D01*
X03661*
X03662Y03296*
X06433*
X03394Y03447D02*
X03441Y034D01*
X04926D02*
X04927Y03401D01*
X03441Y034D02*
X04926D01*
X04927Y03401D02*
X0644D01*
X05049Y03264D02*
X0505Y03266D01*
X03744Y03261D02*
X03747D01*
X0375Y03264*
X05049*
X03687Y02997D02*
X04605D01*
X03468Y03215D02*
X03687Y02997D01*
X02997Y03235D02*
X0323D01*
X02362Y02696D02*
X02494D01*
X02509Y02681*
X02217Y0284D02*
X02362Y02696D01*
X01399Y03075D02*
X01634Y0284D01*
X02217*
X01879Y01811D02*
X03056D01*
X02635Y0179D02*
X02646Y01779D01*
X02579Y0179D02*
X02635D01*
X02385Y032D02*
X02411Y03174D01*
X01459Y03147D02*
X02435D01*
X02205Y032D02*
X02385D01*
X02435Y03147D02*
X0246Y03172D01*
X02405Y03261D02*
X02411Y03266D01*
X02259Y03261D02*
X02405D01*
X03366Y0327D02*
X03367Y03271D01*
X03373D02*
X03374Y03273D01*
X03367Y03271D02*
X03373D01*
X02591Y03186D02*
X02591D01*
X02577Y032D02*
X02591Y03186D01*
X02454Y032D02*
X02577D01*
X02598Y03293D02*
X03252D01*
X0259Y03288D02*
X02593D01*
X02598Y03293*
X03252D02*
X03263Y03303D01*
X0086Y01322D02*
X00996Y01187D01*
X0086Y01322D02*
Y02098D01*
X00997Y02236*
X00996Y02256D02*
X01732D01*
X01739Y02249*
X02499Y02236D02*
X02499Y02236D01*
X02472Y02249D02*
X02494Y0227D01*
X01739Y02249D02*
X02472D01*
X00997Y02236D02*
X02499D01*
X01187Y02314D02*
X02409D01*
X0102Y02481D02*
X01187Y02314D01*
X0181Y01316D02*
X02013D01*
X02016Y01319*
X02004Y01336D02*
X03379D01*
X02028Y01361D02*
X02029Y01361D01*
X02016Y01319D02*
X02499D01*
X00988Y01717D02*
X02588D01*
X02604Y01734*
X02494Y0227D02*
X02529D01*
X02549Y0225D02*
X02608D01*
X02529Y0227D02*
X02549Y0225D01*
X02644Y02272D02*
X02645Y02274D01*
X02629Y02272D02*
X02644D01*
X02608Y0225D02*
X02629Y02272D01*
X02418Y03118D02*
X02428D01*
X02416Y03199D02*
X02429Y03212D01*
X02438*
X0246Y03235*
X02414Y03199D02*
X02416D01*
X0246Y03172D02*
X02462D01*
X02428Y03118D02*
X02577Y02969D01*
X01904Y04017D02*
X02353D01*
X01903Y04018D02*
X01904Y04017D01*
X02002Y04152D02*
X02043D01*
X01965Y04156D02*
X02018Y04209D01*
X02067D02*
X02121Y04156D01*
X02018Y04209D02*
X02067D01*
X02121Y04156D02*
X0397D01*
X0401Y04115*
X01779Y04156D02*
X01965D01*
X02693Y03266D02*
X027Y03273D01*
X02411Y03266D02*
X02693D01*
X02974Y03257D02*
X02997Y03235D01*
X02428Y03174D02*
X02454Y032D01*
X02429Y02621D02*
X02958D01*
X02923Y02481D02*
X02948Y02456D01*
X027Y03273D02*
X03374D01*
X01605Y04136D02*
X01986D01*
X01569Y04171D02*
X01605Y04136D01*
X01986D02*
X02002Y04152D01*
X01769Y00807D02*
X01868Y00906D01*
X01395Y00807D02*
X01769D01*
X01296Y00906D02*
X01395Y00807D01*
X01868Y00906D02*
X02452D01*
X01004D02*
X01296D01*
X03507Y04088D02*
X05267D01*
X03504Y04086D02*
X03507Y04088D01*
X03958Y01512D02*
X03989Y01543D01*
Y01543*
X03994Y01548*
Y01551*
X03897Y01512D02*
X03958D01*
X03963Y01552D02*
X03969D01*
X03951Y01564D02*
X03963Y01552D01*
X0393Y01564D02*
X03951D01*
X01822Y01674D02*
X01882D01*
X01883Y01675*
X02694Y01481D02*
X03543D01*
X03584Y0144*
X03993*
X04064Y01511*
X02384Y01941D02*
X03332D01*
X03357Y01916*
X03569*
X03588Y01897*
X03747*
X03804Y0184*
X0505Y03266D02*
X06334D01*
X02499Y02236D02*
X05634D01*
X02629Y0177D02*
X02633Y01766D01*
X02626Y0177D02*
X02629D01*
X02633Y01766D02*
X03475D01*
X03493Y01784*
X03703*
X03709Y0179*
X03993*
X03999Y01796*
X04064*
X06296Y03115D02*
X06302Y03121D01*
X06304*
X04114Y02661D02*
X0418Y02595D01*
X04132Y01751D02*
X04134D01*
X04116Y01735D02*
X04132Y01751D01*
X03579Y01735D02*
X04116D01*
X03578Y01734D02*
X03579Y01735D01*
X02604Y01734D02*
X03578D01*
X02299Y01916D02*
X03334D01*
X0335Y019*
X03444*
X03453Y01891*
X03554*
X02509Y02681D02*
X04212D01*
X04298Y02595*
X02646Y01779D02*
X03465D01*
X03486Y018*
X03635*
X03651Y01816*
X03944*
X0258Y02412D02*
X02586Y02406D01*
X02575Y02412D02*
X0258D01*
X02586Y02406D02*
X04039D01*
X03499Y01766D02*
X03719D01*
X03483Y0175D02*
X03499Y01766D01*
X02617Y0175D02*
X03483D01*
X02612Y01755D02*
X02617Y0175D01*
X02549Y01755D02*
X02612D01*
X06278Y03226D02*
X06282D01*
X06269Y03235D02*
X06278Y03226D01*
X03806Y03235D02*
X06269D01*
X02423Y03557D02*
X02434Y03546D01*
X0144Y03557D02*
X02423D01*
X03604Y02606D02*
X03623Y02587D01*
X03571Y02606D02*
X03604D01*
X03566Y02601D02*
X03571Y02606D01*
X02821Y02601D02*
X03566D01*
X06342Y03319D02*
X06354Y03331D01*
X03542Y03319D02*
X06342D01*
X03302Y03344D02*
X03612D01*
X03639Y03371D02*
X06409D01*
X03612Y03344D02*
X03639Y03371D01*
X03457Y03436D02*
X06469D01*
X03436Y03457D02*
X03457Y03436D01*
X06469D02*
X06479Y03426D01*
X038Y032D02*
X06308D01*
X03431Y01682D02*
X03599D01*
X03429Y0168D02*
X03431Y01682D01*
X03202Y01673D02*
X03211Y01681D01*
X03204Y01693D02*
X03205Y01694D01*
X03599Y01682D02*
X03606Y01675D01*
X03419Y01693D02*
X03436Y01711D01*
X01893Y01693D02*
X03204D01*
X03606Y01675D02*
X03724D01*
X01885Y01673D02*
X03202D01*
X01883Y01675D02*
X01885Y01673D01*
X03205Y01694D02*
X03312D01*
X03312Y01693*
X03419*
X03307Y0168D02*
X03429D01*
X03306Y01681D02*
X03307Y0168D01*
X03211Y01681D02*
X03306D01*
X03436Y01711D02*
X03589D01*
X02667Y01641D02*
X03782D01*
X03792Y01651*
X03082Y01591D02*
X03091Y016D01*
X03699D02*
X03705Y01606D01*
X03091Y016D02*
X03699D01*
X06445Y03396D02*
X06447D01*
X0644Y03401D02*
X06445Y03396D01*
X02478Y00932D02*
Y00937D01*
X02452Y00906D02*
X02478Y00932D01*
X02719Y01591D02*
X03082D01*
X02919Y01536D02*
X03873D01*
X03897Y01512*
X06333Y03155D02*
X06337Y03151D01*
X0406Y03155D02*
X06333D01*
X06337Y03151D02*
X06339D01*
X02702Y03257D02*
X02974D01*
X0246Y03235D02*
X0268D01*
X02702Y03257*
X02666Y0164D02*
X02667Y01641D01*
X02411Y03174D02*
X02428D01*
X01008Y0143D02*
X0101D01*
X02274Y01506D02*
X03544D01*
X01017Y01437D02*
X02446D01*
X0101Y0143D02*
X01017Y01437D01*
X02059Y01386D02*
X03379D01*
X03402Y01361D02*
X03404Y01363D01*
X02029Y01361D02*
X03402D01*
X02499Y01319D02*
X02502Y01316D01*
X02525Y02463D02*
X02598D01*
X02616Y02481D02*
X02923D01*
X02598Y02463D02*
X02616Y02481D01*
X02841Y02263D02*
X03342D01*
X02803Y02307D02*
X02837Y02341D01*
X03498*
X01009Y01956D02*
X0102Y01967D01*
X02409*
X02643Y01616D02*
X03469D01*
X02557Y03616D02*
X02799D01*
X02129Y03587D02*
X02257D01*
X023Y03629*
X02543*
X02557Y03616*
X02123Y03571D02*
X02611D01*
X02636Y03596*
X01754Y03661D02*
X01755Y03661D01*
X02679*
X02679Y03661*
X01549Y03621D02*
X0187D01*
X01895Y03645*
X02652*
X02115Y03601D02*
X02129Y03587D01*
X01593Y03577D02*
X02117D01*
X02652Y03645D02*
X02661Y03636D01*
X03424*
X01884Y03601D02*
X02115D01*
X02117Y03577D02*
X02123Y03571D01*
X02636Y03596D02*
X03239D01*
X01574D02*
X01593Y03577D01*
X02525Y03506D02*
X02569Y03462D01*
X03037D02*
X03056Y03481D01*
X03529*
X02569Y03462D02*
X03037D01*
X02234Y03506D02*
X02525D01*
X02993Y03751D02*
X03699D01*
X03019Y03836D02*
X03699D01*
X03014Y03831D02*
X03019Y03836D01*
X03014Y03831D02*
Y03831D01*
X02894Y01561D02*
X03327D01*
X03336Y01552D02*
X03769D01*
X03327Y01561D02*
X03336Y01552D01*
X03769D02*
X03807Y0159D01*
X03904D02*
X0393Y01564D01*
X03807Y0159D02*
X03904D01*
X03959Y01599D02*
X04178D01*
X03952Y01606D02*
X03959Y01599D01*
X03705Y01606D02*
X03952D01*
X03544Y01506D02*
X03594Y01456D01*
X03922*
X03939Y01473*
X03961D02*
X04034Y01546D01*
X03939Y01473D02*
X03961D01*
X04178Y01599D02*
X04179Y01601D01*
X03469Y01616D02*
X03477Y01623D01*
X04151*
X03792Y01651D02*
X04134D01*
X03799Y03201D02*
X038Y032D01*
X06308D02*
X06309Y03199D01*
X0401Y04115D02*
X04754D01*
X03829Y03176D02*
X06274D01*
X06275Y03175*
X06377Y03191D02*
X06439D01*
X06361Y03175D02*
X06377Y03191D01*
X06275Y03175D02*
X06361D01*
X06433Y03296D02*
X06438Y03291D01*
X06444*
X03469Y03456D02*
X06509D01*
G54D21*
X02589Y00324D02*
D01*
X02589Y00325*
X02589Y00325*
X02589Y00325*
X02589Y00326*
X0259Y00326*
X0259Y00326*
X0259Y00327*
X0259Y00327*
X02583Y00303D02*
D01*
X02583Y00304*
X02583Y00304*
X02583Y00304*
X02583Y00305*
X02584Y00305*
X02584Y00305*
X02577Y00297D02*
D01*
X02575Y00297*
X02574Y00297*
X02573Y00297*
X02572Y00296*
X02571Y00296*
X02569Y00295*
X02568Y00295*
X02567Y00294*
X02566Y00293*
X02565Y00292*
X02564Y00291*
X02564Y0029*
X02563Y00289*
X02562Y00288*
X02562Y00287*
X02561Y00286*
X02561Y00285*
X0256Y00283*
X0256Y00282*
X0256Y00281*
X0256Y00279*
X0256Y00278*
X0256Y00277*
X0256Y00276*
X0256Y00274*
X02561Y00273*
X02561Y00272*
X02562Y00271*
X02562Y0027*
X02563Y00269*
X02564Y00267*
X02565Y00266*
X02566Y00266*
X02567Y00265*
X02568Y00264*
X02569Y00263*
X0257Y00263*
X02571Y00262*
X02572Y00262*
X02573Y00261*
X02575Y00261*
X02576Y00261*
X02577Y00261*
X02578Y00261*
X0258Y00261*
X02581Y00261*
X02582Y00261*
X02584Y00261*
X02585Y00262*
X02586Y00262*
X02587Y00263*
X02588Y00263*
X02589Y00264*
X0259Y00265*
X02591Y00266*
X02592Y00267*
X02593Y00268*
X02594Y00269*
X02594Y0027*
X02595Y00271*
X02595Y00272*
X02596Y00274*
X02596Y00275*
X02583Y00303D02*
D01*
X02581Y00301*
X02581Y003*
X026Y00278D02*
D01*
X02599Y00278*
X02599Y00278*
X02599Y00278*
X02598Y00278*
X02598Y00277*
X02598Y00277*
X02598Y00277*
X02597Y00277*
X02597Y00276*
X02597Y00276*
X02597Y00276*
X02597Y00276*
X02596Y00275*
X02596Y00275*
X02596Y00275*
X02577Y00297D02*
D01*
X02577Y00298*
X02577Y00298*
X02578Y00298*
X02578Y00298*
X02578Y00298*
X02579Y00298*
X02579Y00298*
X02579Y00298*
X0258Y00299*
X0258Y00299*
X0258Y00299*
X0258Y00299*
X0258Y003*
X02581Y003*
X02589Y00324D02*
D01*
X02588Y00323*
X02588Y00322*
X02588Y00321*
X02587Y0032*
X02604Y00279D02*
D01*
X02603Y00279*
X02602Y00279*
X02601Y00279*
X026Y00278*
X026Y00278*
X02578Y00279D02*
D01*
X02582Y00283*
X02586Y00288*
X02589Y00292*
X02591Y00295*
X02602Y00376D02*
D01*
X02602Y00376*
X02602Y00375*
X02602Y00374*
X02602Y00374*
X02602Y00373*
X02603Y00373*
X02603Y00373*
X02603Y00372*
X02603Y00372*
X02604Y00371*
X02604Y00371*
X02604Y0037*
X02605Y0037*
X02605Y0037*
X02606Y0037*
X02606Y00369*
X02607Y00369*
X02607Y00369*
X02608Y00369*
X02608Y00369*
X02609Y00369*
X02609Y00369*
X02609Y00369*
X02616Y00354D02*
D01*
X02616Y00354*
X02617Y00354*
X02617Y00354*
X02618Y00354*
X02618Y00354*
X02619Y00354*
X02619Y00354*
X0262Y00355*
X0262Y00355*
X0262Y00355*
X02621Y00356*
X02621Y00356*
X02622Y00356*
X02622Y00357*
X02622Y00357*
X02622Y00358*
X02623Y00358*
X02623Y00359*
X02623Y00359*
X02623Y0036*
X02623Y0036*
X02623Y00361*
Y00361*
X02623Y00362*
X02623Y00362*
X02623Y00363*
X02623Y00363*
X02623Y00364*
X02622Y00364*
X02622Y00365*
X02622Y00365*
X02622Y00366*
X02621Y00366*
X02621Y00366*
X0262Y00367*
X0262Y00367*
X0262Y00367*
X02619Y00368*
X02619Y00368*
X02618Y00368*
X02618Y00368*
X02617Y00368*
X02617Y00368*
X02616Y00369*
X02616Y00369*
X02607Y00354D02*
D01*
X02607Y00354*
X02606Y00353*
X02606Y00353*
X02605Y00353*
X02604Y00353*
X02604Y00353*
X02604Y00353*
X02603Y00352*
X02603Y00352*
X02602Y00352*
X02602Y00351*
X02601Y00351*
X02601Y00351*
X02601Y0035*
X02601Y0035*
X026Y00349*
X026Y00349*
X026Y00348*
X026Y00348*
X026Y00347*
X026Y00347*
X026Y00346*
Y00346*
X026Y00345*
X026Y00345*
X026Y00344*
X026Y00344*
X026Y00343*
X026Y00343*
X02601Y00342*
X02601Y00342*
X02601Y00341*
X02601Y00341*
X02602Y00341*
X02602Y0034*
X02603Y0034*
X02603Y0034*
X02604Y00339*
X02604Y00339*
X02604Y00339*
X02605Y00339*
X02606Y00339*
X02606Y00339*
X02607Y00339*
X02607Y00339*
X02619Y00324D02*
D01*
X0262Y00324*
X0262Y00324*
X02621Y00324*
X02621Y00324*
X02622Y00324*
X02622Y00324*
X02623Y00324*
X02623Y00325*
X02624Y00325*
X02624Y00325*
X02624Y00326*
X02625Y00326*
X02625Y00326*
X02625Y00327*
X02626Y00327*
X02626Y00328*
X02626Y00328*
X02626Y00329*
X02627Y00329*
X02627Y0033*
X02627Y0033*
X02627Y00331*
Y00331*
X02627Y00332*
X02627Y00332*
X02627Y00333*
X02626Y00333*
X02626Y00334*
X02626Y00334*
X02626Y00335*
X02625Y00335*
X02625Y00336*
X02625Y00336*
X02624Y00336*
X02624Y00337*
X02624Y00337*
X02623Y00337*
X02623Y00338*
X02622Y00338*
X02622Y00338*
X02621Y00338*
X02621Y00338*
X0262Y00338*
X0262Y00339*
X02619Y00339*
X02604Y00324D02*
D01*
X02604Y00324*
X02603Y00323*
X02603Y00323*
X02602Y00323*
X02602Y00323*
X02601Y00323*
X02601Y00323*
X026Y00322*
X026Y00322*
X026Y00322*
X02599Y00321*
X02599Y00321*
X02598Y00321*
X02598Y0032*
X02598Y0032*
X02598Y00319*
X02597Y00319*
X02597Y00318*
X02597Y00318*
X02591Y00295D02*
D01*
X02591Y00295*
X02591Y00296*
X02591Y00296*
X02592Y00297*
X02592Y00297*
X02608Y00457D02*
D01*
X02604Y0045*
X026Y00444*
X02597Y00437*
X02595Y0043*
X02593Y00422*
X02591Y00415*
X0259Y00408*
X0259Y00404*
D01*
X0259Y00404*
X0259Y00404*
X02633Y00472D02*
D01*
X02628Y00467*
X02623Y00461*
X02619Y00455*
X02615Y00448*
X02612Y00442*
X02609Y00435*
X02607Y00428*
X02605Y0042*
X02603Y00413*
X02602Y00406*
X02602Y00398*
X02602Y00396*
X02625Y0048D02*
D01*
X0262Y00474*
X02616Y00469*
X02612Y00463*
X02608Y00457*
X02909Y00366D02*
D01*
X02909Y00366*
X02909Y00365*
X02909Y00365*
X02909Y00364*
X02909Y00364*
X02909Y00363*
X02909Y00363*
X0291Y00362*
X0291Y00362*
X0291Y00362*
X02911Y00361*
X02911Y00361*
X02912Y00361*
X02912Y0036*
X02912Y0036*
X02913Y0036*
X02913Y00359*
X02914Y00359*
X02914Y00359*
X02915Y00359*
X02915Y00359*
X02916Y00359*
X02916Y00359*
Y00344D02*
D01*
X02917Y00344*
X02917Y00344*
X02918Y00344*
X02918Y00344*
X02919Y00344*
X02919Y00345*
X0292Y00345*
X0292Y00345*
X02921Y00345*
X02921Y00346*
X02921Y00346*
X02922Y00346*
X02922Y00347*
X02922Y00347*
X02923Y00348*
X02923Y00348*
X02923Y00349*
X02923Y00349*
X02923Y0035*
X02924Y0035*
X02924Y00351*
X02924Y00351*
Y00352*
X02924Y00352*
X02924Y00353*
X02923Y00353*
X02923Y00354*
X02923Y00354*
X02923Y00355*
X02923Y00355*
X02922Y00356*
X02922Y00356*
X02922Y00356*
X02921Y00357*
X02921Y00357*
X02921Y00358*
X0292Y00358*
X0292Y00358*
X02919Y00358*
X02919Y00358*
X02918Y00359*
X02918Y00359*
X02917Y00359*
X02917Y00359*
X02916Y00359*
X02903Y00344D02*
D01*
X02902Y00344*
X02902Y00344*
X02901Y00344*
X02901Y00344*
X029Y00343*
X029Y00343*
X02899Y00343*
X02899Y00343*
X02898Y00343*
X02898Y00342*
X02898Y00342*
X02897Y00341*
X02897Y00341*
X02897Y00341*
X02896Y0034*
X02896Y0034*
X02896Y00339*
X02896Y00339*
X02896Y00338*
X02895Y00338*
X02895Y00337*
X02895Y00337*
Y00336*
X02895Y00336*
X02895Y00335*
X02896Y00335*
X02896Y00334*
X02896Y00334*
X02896Y00333*
X02896Y00333*
X02897Y00332*
X02897Y00332*
X02897Y00331*
X02898Y00331*
X02898Y00331*
X02898Y0033*
X02899Y0033*
X02899Y0033*
X029Y0033*
X029Y00329*
X02901Y00329*
X02901Y00329*
X02902Y00329*
X02902Y00329*
X02903Y00329*
X02915Y00314D02*
D01*
X02915Y00314*
X02916Y00314*
X02916Y00314*
X02917Y00314*
X02917Y00314*
X02918Y00315*
X02918Y00315*
X02918Y00315*
X02919Y00315*
X02919Y00316*
X0292Y00316*
X0292Y00316*
X0292Y00317*
X02921Y00317*
X02921Y00318*
X02921Y00318*
X02921Y00319*
X02922Y00319*
X02922Y0032*
X02922Y0032*
X02922Y00321*
X02922Y00321*
Y00322*
X02922Y00322*
X02922Y00323*
X02922Y00323*
X02922Y00324*
X02921Y00324*
X02921Y00325*
X02921Y00325*
X02921Y00326*
X0292Y00326*
X0292Y00326*
X0292Y00327*
X02919Y00327*
X02919Y00328*
X02918Y00328*
X02918Y00328*
X02918Y00328*
X02917Y00328*
X02917Y00329*
X02916Y00329*
X02916Y00329*
X02915Y00329*
X02915Y00329*
X02905Y00314D02*
D01*
X02904Y00314*
X02904Y00314*
X02903Y00314*
X02903Y00314*
X02902Y00313*
X02902Y00313*
X02901Y00313*
X02901Y00313*
X029Y00313*
X029Y00312*
X02899Y00312*
X02899Y00311*
X02899Y00311*
X02898Y00311*
X02898Y0031*
X02898Y0031*
X02898Y00309*
X02898Y00309*
X02897Y00308*
X02897Y00308*
X02897Y00307*
X02897Y00307*
X02897Y00306*
X02926Y004D02*
D01*
X02927Y00401*
X02927Y00401*
X02927Y00401*
X02927Y00402*
X02927Y00402*
X02927Y00402*
X02928Y00403*
X02928Y00403*
X02928Y00403*
X02928Y00404*
X02928Y00404*
X02928Y00404*
X02885Y00274D02*
D01*
X02886Y00273*
X02886Y00272*
X02887Y00271*
X02888Y00269*
X02888Y00268*
X02889Y00267*
X0289Y00266*
X02891Y00265*
X02892Y00264*
X02893Y00263*
X02894Y00263*
X02895Y00262*
X02896Y00261*
X02898Y00261*
X02899Y00261*
X029Y0026*
X02902Y0026*
X02903Y0026*
X02904Y0026*
X02906Y0026*
X02907Y0026*
X02908Y0026*
X0291Y00261*
X02911Y00261*
X02912Y00262*
X02913Y00262*
X02915Y00263*
X02916Y00264*
X02917Y00264*
X02918Y00265*
X02919Y00266*
X02919Y00267*
X0292Y00268*
X02921Y0027*
X02922Y00271*
X02922Y00272*
X02923Y00273*
X02923Y00275*
X02923Y00275*
X02911Y004D02*
D01*
X02911Y004*
X02911Y004*
X02911Y00401*
X02912Y00401*
X02912Y00401*
X02912Y00401*
X02912Y00402*
X02911Y004D02*
D01*
X02907Y00397*
X02904Y00395*
X02901Y00392*
X02899Y00389*
X02896Y00386*
X02894Y00382*
X02892Y00379*
X0289Y00375*
X02889Y00372*
X02888Y00368*
X02887Y00364*
X02886Y0036*
X02885Y00356*
X02885Y00352*
X02912Y00402D02*
D01*
X02913Y00404*
X02914Y00406*
X02915Y00408*
X02916Y0041*
X02916Y00413*
X02917Y00415*
X02917Y00418*
X02917Y00419*
X02928Y00834D02*
D01*
X02928Y00835*
X02928Y00836*
X02928Y00836*
X02927Y00837*
X02927Y00838*
X02927Y00839*
X02927Y00839*
X02926Y0084*
X02926Y00841*
X02925Y00841*
X02925Y00842*
X02925Y00842*
X02897Y00289D02*
D01*
X02897Y00289*
X02897Y00288*
X02897Y00288*
X02897Y00288*
X02897Y00287*
X02898Y00287*
X02898Y00287*
X02898Y00286*
X02898Y00286*
X02898Y00286*
X02899Y00285*
X02899Y00285*
X02759Y0094D02*
D01*
X02759Y00938*
X02759Y00935*
X0276Y00933*
X0276Y0093*
X02761Y00928*
X02762Y00925*
X02763Y00923*
X02765Y00921*
X02766Y00919*
X02768Y00917*
X02769Y00915*
X0277Y00914*
X02767Y00976D02*
D01*
X02766Y00974*
X02765Y00973*
X02764Y00971*
X02762Y00969*
X02762Y00968*
X02761Y00966*
X0276Y00964*
X0276Y00962*
X02759Y0096*
X02759Y00958*
X02759Y00956*
X02759Y00956*
X02915Y00852D02*
D01*
X02912Y00854*
X0291Y00856*
X02907Y00858*
X02904Y0086*
X02901Y00861*
X02898Y00863*
X02895Y00864*
X02892Y00864*
X02889Y00865*
X02886Y00865*
X02882Y00866*
X02881Y00866*
X02789Y00895D02*
D01*
X02794Y0089*
X028Y00886*
X02805Y00882*
X02811Y00878*
X02818Y00875*
X02824Y00872*
X02831Y0087*
X02837Y00868*
X02844Y00867*
X02851Y00866*
X02858Y00866*
X0286Y00866*
X02748Y00285D02*
D01*
X02748Y00284*
X02748Y00284*
X02748Y00283*
X02748Y00283*
X02748Y00283*
X02748Y00282*
X02748Y00282*
X02748Y00282*
X02748Y00282*
X02737Y00267D02*
D01*
X02738Y00266*
X02739Y00265*
X0274Y00265*
X02741Y00264*
X02742Y00263*
X02743Y00263*
X02744Y00263*
X02745Y00262*
X02746Y00262*
X02747Y00262*
X02749Y00262*
X0275Y00262*
X02751Y00262*
X02752Y00262*
X02753Y00262*
X02754Y00263*
X02755Y00263*
X02757Y00264*
X02758Y00264*
X02759Y00265*
X0276Y00265*
X0276Y00266*
X02761Y00267*
X02762Y00268*
X02763Y00269*
X02763Y0027*
X02764Y00271*
X02765Y00272*
X02765Y00273*
X02765Y00274*
X02766Y00275*
X02737Y00387D02*
D01*
X02733Y00383*
X0273Y00378*
X02726Y00373*
X02723Y00368*
X0272Y00363*
X02718Y00357*
X02716Y00352*
X02715Y00346*
X02714Y0034*
X02713Y00334*
X02713Y00329*
X02713Y00327*
D01*
X02713Y00321*
X02713Y00315*
X02714Y00309*
X02716Y00303*
X02718Y00297*
X0272Y00292*
X02723Y00286*
X02726Y00281*
X02729Y00276*
X02733Y00271*
X02737Y00267*
X02737Y00267*
X0274Y00348D02*
D01*
X02741Y00348*
X02741Y00348*
X02742Y00348*
X02742Y00348*
X02743Y00348*
X02743Y00348*
X02744Y00348*
X02744Y00349*
X02744Y00349*
X02745Y00349*
X02745Y0035*
X02746Y0035*
X02746Y00351*
X02746Y00351*
X02747Y00351*
X02747Y00352*
X02747Y00352*
X02747Y00353*
X02747Y00353*
X02747Y00354*
X02748Y00354*
X02748Y00355*
X02748Y00355*
X02733Y00348D02*
D01*
X02733Y00348*
X02732Y00348*
X02732Y00347*
X02731Y00347*
X02731Y00347*
X0273Y00347*
X0273Y00347*
X02729Y00346*
X02729Y00346*
X02729Y00346*
X02728Y00346*
X02728Y00345*
X02728Y00345*
X02727Y00344*
X02727Y00344*
X02727Y00343*
X02726Y00343*
X02726Y00342*
X02726Y00342*
X02726Y00341*
X02726Y00341*
X02726Y0034*
Y0034*
X02726Y00339*
X02726Y00339*
X02726Y00338*
X02726Y00338*
X02726Y00337*
X02727Y00337*
X02727Y00336*
X02727Y00336*
X02728Y00336*
X02728Y00335*
X02728Y00335*
X02729Y00334*
X02729Y00334*
X02729Y00334*
X0273Y00333*
X0273Y00333*
X02731Y00333*
X02731Y00333*
X02732Y00333*
X02732Y00333*
X02733Y00333*
X02733Y00333*
X0275Y00318D02*
D01*
X02751Y00318*
X02751Y00318*
X02752Y00318*
X02752Y00318*
X02753Y00318*
X02753Y00318*
X02754Y00318*
X02754Y00319*
X02754Y00319*
X02755Y00319*
X02755Y0032*
X02756Y0032*
X02756Y00321*
X02756Y00321*
X02757Y00321*
X02757Y00322*
X02757Y00322*
X02757Y00323*
X02757Y00323*
X02757Y00324*
X02758Y00324*
X02758Y00325*
Y00325*
X02758Y00326*
X02757Y00326*
X02757Y00327*
X02757Y00327*
X02757Y00328*
X02757Y00328*
X02757Y00329*
X02756Y00329*
X02756Y0033*
X02756Y0033*
X02755Y00331*
X02755Y00331*
X02754Y00331*
X02754Y00331*
X02754Y00332*
X02753Y00332*
X02753Y00332*
X02752Y00332*
X02752Y00332*
X02751Y00333*
X02751Y00333*
X0275Y00333*
X02733Y00318D02*
D01*
X02733Y00318*
X02732Y00318*
X02732Y00317*
X02731Y00317*
X02731Y00317*
X0273Y00317*
X0273Y00317*
X02729Y00316*
X02729Y00316*
X02729Y00316*
X02728Y00316*
X02728Y00315*
X02728Y00315*
X02727Y00314*
X02727Y00314*
X02727Y00313*
X02726Y00313*
X02726Y00312*
X02726Y00312*
X02726Y00311*
X02726Y00311*
X02726Y0031*
Y0031*
X02726Y00309*
X02726Y00309*
X02726Y00308*
X02726Y00308*
X02726Y00307*
X02727Y00307*
X02727Y00306*
X02727Y00306*
X02728Y00306*
X02728Y00305*
X02728Y00305*
X02729Y00304*
X02729Y00304*
X02729Y00304*
X0273Y00303*
X0273Y00303*
X02731Y00303*
X02731Y00303*
X02732Y00303*
X02732Y00303*
X02733Y00303*
X02733Y00303*
X02748Y00295D02*
D01*
X02748Y00296*
X02747Y00296*
X02747Y00297*
X02747Y00297*
X02747Y00298*
X02747Y00298*
X02747Y00299*
X02746Y00299*
X02746Y003*
X02746Y003*
X02745Y003*
X02745Y00301*
X02745Y00301*
X02744Y00301*
X02744Y00302*
X02743Y00302*
X02743Y00302*
X02742Y00302*
X02742Y00302*
X02741Y00302*
X02741Y00303*
X0274Y00303*
X0274Y00303*
X02749Y00383D02*
D01*
X02749Y00383*
X02749Y00383*
X02748Y00382*
X02748Y00382*
X02748Y00382*
X02748Y00381*
X02748Y00381*
X02748Y00381*
X02748Y0038*
X02748Y0038*
X02748Y0038*
X02748Y0038*
X02515Y0036D02*
D01*
X02515Y0036*
X02516Y00359*
X02516Y00359*
X02517Y00359*
X02517Y00359*
X02518Y00358*
X02518Y00358*
X02519Y00358*
X02519Y00358*
X0252Y00358*
X0252Y00358*
X02521Y00358*
X02521Y00358*
X02522Y00358*
X02522Y00358*
X02523Y00358*
X02523Y00359*
X02524Y00359*
X02524Y00359*
X02525Y00359*
X02525Y0036*
X02525Y0036*
X02526Y0036*
X02515D02*
D01*
X02515Y00361*
X02514Y00361*
X02514Y00361*
X02513Y00361*
X02513Y00362*
X02512Y00362*
X02512Y00362*
X02511Y00362*
X02511Y00362*
X0251Y00362*
X0251Y00362*
X02509Y00362*
X02509Y00362*
X02508Y00362*
X02508Y00362*
X02507Y00362*
X02507Y00362*
X02506Y00362*
X02506Y00361*
X02505Y00361*
X02505Y00361*
X02505Y0036*
X02504Y0036*
D01*
X02504Y0036*
X02504Y00359*
X02503Y00359*
X02503Y00359*
X02503Y00358*
X02503Y00358*
X02502Y00357*
X02502Y00357*
X02502Y00356*
X02502Y00356*
X02502Y00355*
X02502Y00354*
X02502Y00354*
X02502Y00353*
X02502Y00353*
X02503Y00352*
X02503Y00352*
X02503Y00351*
X02503Y00351*
X02503Y00351*
X02504Y0035*
X02504Y0035*
X02504Y0035*
Y00339D02*
D01*
X02505Y00339*
X02505Y0034*
X02505Y0034*
X02506Y00341*
X02506Y00341*
X02506Y00342*
X02506Y00342*
X02506Y00343*
X02506Y00343*
X02506Y00344*
X02507Y00344*
X02507Y00345*
X02506Y00345*
X02506Y00346*
X02506Y00346*
X02506Y00347*
X02506Y00347*
X02506Y00348*
X02505Y00348*
X02505Y00349*
X02505Y00349*
X02505Y00349*
X02504Y0035*
X02494Y00339D02*
D01*
X02494Y00339*
X02495Y00338*
X02495Y00338*
X02495Y00338*
X02496Y00337*
X02496Y00337*
X02497Y00337*
X02497Y00337*
X02498Y00337*
X02498Y00337*
X02499Y00337*
X02499Y00337*
X025Y00337*
X025Y00337*
X02501Y00337*
X02501Y00337*
X02502Y00337*
X02502Y00338*
X02503Y00338*
X02503Y00338*
X02504Y00338*
X02504Y00339*
X02504Y00339*
X02491Y00341D02*
D01*
X02491Y00342*
X0249Y00342*
X0249Y00342*
X0249Y00343*
X02489Y00343*
X02489Y00343*
X02488Y00343*
X02488Y00343*
X02487Y00344*
X02487Y00344*
X02486Y00344*
X02486Y00344*
X02485Y00344*
X02485Y00343*
X02484Y00343*
X02484Y00343*
X02483Y00343*
X02483Y00343*
X02482Y00343*
X02482Y00342*
X02481Y00342*
X02481Y00342*
X02481Y00341*
D01*
X0248Y00341*
X0248Y00341*
X0248Y0034*
X02479Y0034*
X02479Y00339*
X02479Y00339*
X02479Y00338*
X02479Y00338*
X02479Y00337*
X02478Y00337*
X02478Y00336*
X02478Y00336*
X02479Y00335*
X02479Y00335*
X02479Y00334*
X02479Y00334*
X02479Y00333*
X02479Y00333*
X0248Y00332*
X0248Y00332*
X0248Y00331*
X0248Y00331*
X02481Y00331*
X02483Y00318D02*
D01*
X02483Y00318*
X02484Y00319*
X02484Y00319*
X02484Y00319*
X02485Y0032*
X02485Y0032*
X02485Y00321*
X02485Y00321*
X02485Y00322*
X02485Y00322*
X02485Y00323*
X02485Y00323*
X02485Y00324*
X02485Y00324*
X02485Y00325*
X02485Y00326*
X02485Y00326*
X02484Y00326*
X02484Y00327*
X02484Y00327*
X02484Y00328*
X02483Y00328*
X02483Y00328*
X02473Y00318D02*
D01*
X02473Y00317*
X02473Y00317*
X02474Y00317*
X02474Y00317*
X02475Y00316*
X02475Y00316*
X02476Y00316*
X02476Y00316*
X02477Y00316*
X02477Y00316*
X02478Y00316*
X02478Y00316*
X02479Y00316*
X02479Y00316*
X0248Y00316*
X0248Y00316*
X02481Y00316*
X02481Y00316*
X02482Y00317*
X02482Y00317*
X02483Y00317*
X02483Y00318*
X02483Y00318*
X02469Y00321D02*
D01*
X02469Y00321*
X02468Y00322*
X02468Y00322*
X02468Y00322*
X02467Y00323*
X02467Y00323*
X02466Y00323*
X02466Y00323*
X02465Y00323*
X02465Y00323*
X02464Y00323*
X02464Y00323*
X02463Y00323*
X02462Y00323*
X02462Y00323*
X02461Y00323*
X02461Y00323*
X02461Y00322*
X0246Y00322*
X0246Y00322*
X02459Y00322*
X02459Y00321*
X02459Y00321*
D01*
X02458Y00321*
X02458Y0032*
X02458Y0032*
X02457Y00319*
X02457Y00319*
X02457Y00318*
X02457Y00318*
X02457Y00317*
X02456Y00317*
X02456Y00316*
X02456Y00316*
X02456Y00315*
X02456Y00315*
X02457Y00314*
X02457Y00314*
X02457Y00313*
X02457Y00313*
X02457Y00312*
X02457Y00312*
X02458Y00311*
X02458Y00311*
X02458Y00311*
X02459Y0031*
X02462Y00297D02*
D01*
X02462Y00297*
X02463Y00297*
X02463Y00298*
X02463Y00298*
X02463Y00299*
X02464Y00299*
X02464Y003*
X02464Y003*
X02464Y00301*
X02464Y00301*
X02464Y00302*
X02464Y00302*
X02464Y00303*
X02464Y00303*
X02464Y00304*
X02464Y00304*
X02463Y00305*
X02463Y00305*
X02463Y00306*
X02463Y00306*
X02462Y00307*
X02462Y00307*
X02462Y00307*
X02885Y00276D02*
D01*
X02885Y00275*
X02885Y00275*
X02885Y00275*
X02885Y00274*
X02928Y00279D02*
D01*
X02928Y00279*
X02927Y00279*
X02927Y00279*
X02927Y00279*
X02926Y00279*
X02926Y00279*
X02926Y00278*
X02925Y00278*
X02925Y00278*
X02925Y00278*
X02925Y00278*
X02924Y00277*
X02924Y00277*
X02924Y00277*
X02924Y00277*
X02923Y00276*
X02923Y00276*
X02923Y00276*
X02923Y00275*
X02923Y00275*
X02771Y00279D02*
D01*
X0277Y00279*
X0277Y00279*
X02769Y00279*
X02769Y00279*
X02769Y00279*
X02768Y00279*
X02768Y00278*
X02768Y00278*
X02768Y00278*
X02767Y00278*
X02767Y00278*
X02767Y00277*
X02767Y00277*
X02766Y00277*
X02766Y00277*
X02766Y00276*
X02766Y00276*
X02766Y00276*
X02766Y00275*
X02766Y00275*
X02692Y00795D02*
D01*
X02691Y00793*
X0269Y00792*
X02689Y0079*
X02688Y00788*
X02687Y00787*
X02686Y00785*
X02685Y00783*
X02685Y00781*
X02684Y00779*
X02684Y00777*
X02684Y00775*
X02684Y00775*
X02652Y0049D02*
D01*
X02657Y00496*
X02662Y00502*
X02666Y00508*
X0267Y00515*
X02674Y00522*
X02677Y00529*
X02679Y00536*
X02681Y00544*
X02683Y00551*
X02684Y00559*
X02684Y00567*
X02684Y00569*
X02673Y00775D02*
D01*
X02673Y00777*
X02673Y00779*
X02673Y00781*
X02672Y00782*
X02671Y00784*
X02671Y00786*
X0267Y00788*
X02669Y0079*
X02668Y00791*
X02667Y00793*
X02665Y00794*
X02665Y00795*
X02644Y00498D02*
D01*
X02649Y00503*
X02653Y00509*
X02657Y00514*
X02661Y0052*
X02664Y00527*
X02666Y00533*
X02669Y0054*
X02671Y00546*
X02672Y00553*
X02673Y0056*
X02673Y00567*
X02673Y00569*
X02563Y00383D02*
D01*
X02563Y00384*
X02564Y00385*
X02565Y00385*
X02565Y00386*
X02565Y00387*
X02566Y00388*
X02566Y00389*
X02566Y00389*
X02566Y0039*
X02566Y0039*
X02464Y00285D02*
D01*
X02464Y00284*
X02464Y00284*
X02464Y00284*
X02463Y00284*
X02463Y00283*
X02463Y00283*
X02463Y00283*
X02463Y00282*
X02463Y00282*
X02463Y00282*
X02463Y00281*
X02463Y00281*
X02463Y00281*
X02578Y0083D02*
D01*
X02576Y00828*
X02574Y00826*
X02573Y00824*
X02571Y00821*
X0257Y00819*
X02569Y00816*
X02568Y00814*
X02567Y00811*
X02567Y00808*
X02567Y00806*
X02566Y00803*
X02566Y00802*
X02807Y00775D02*
D01*
X02807Y00777*
X02807Y00779*
X02806Y00781*
X02806Y00782*
X02805Y00784*
X02805Y00786*
X02804Y00788*
X02803Y0079*
X02802Y00791*
X028Y00793*
X02799Y00794*
X02799Y00795*
X02795Y00429D02*
D01*
X02798Y00433*
X02802Y00437*
X02805Y00442*
X02808Y00446*
X02811Y00451*
X02813Y00456*
X02815Y00462*
X02816Y00467*
X02817Y00473*
X02818Y00478*
X02818Y00484*
X02818Y00485*
X02826Y00795D02*
D01*
X02825Y00793*
X02824Y00792*
X02823Y0079*
X02822Y00788*
X02821Y00787*
X0282Y00785*
X02819Y00783*
X02819Y00781*
X02818Y00779*
X02818Y00777*
X02818Y00775*
X02818Y00775*
X02787Y00437D02*
D01*
X0279Y0044*
X02793Y00444*
X02796Y00448*
X02798Y00452*
X02801Y00456*
X02802Y0046*
X02804Y00465*
X02805Y0047*
X02806Y00474*
X02807Y00479*
X02807Y00484*
X02807Y00485*
X02426Y00275D02*
D01*
X02427Y00274*
X02427Y00273*
X02428Y00271*
X02428Y0027*
X02429Y00269*
X02429Y00268*
X0243Y00267*
X02431Y00266*
X02432Y00265*
X02433Y00264*
X02434Y00264*
X02435Y00263*
X02436Y00262*
X02438Y00262*
X02439Y00261*
X0244Y00261*
X02441Y00261*
X02443Y00261*
X02444Y00261*
X02445Y00261*
X02446Y00261*
X02448Y00261*
X02449Y00261*
X0245Y00261*
X02451Y00262*
X02453Y00262*
X02454Y00263*
X02455Y00264*
X02456Y00265*
X02457Y00265*
X02458Y00266*
X02459Y00267*
X02459Y00268*
X0246Y00269*
X02461Y0027*
X02461Y00272*
X02462Y00273*
X02462Y00274*
X02463Y00275*
X02463Y00277*
X02463Y00278*
X02463Y00279*
X02463Y0028*
X02463Y00281*
X02553Y00388D02*
D01*
X02554Y00388*
X02554Y00389*
X02554Y00389*
X02554Y0039*
X02555Y0039*
X02555Y00391*
X02555Y00391*
X02555Y00392*
X02555Y00392*
X02555Y00393*
X02555Y00393*
Y00393*
X0257Y00838D02*
D01*
X02568Y00835*
X02566Y00833*
X02564Y0083*
X02562Y00827*
X0256Y00824*
X02559Y0082*
X02558Y00817*
X02557Y00814*
X02556Y0081*
X02556Y00806*
X02555Y00803*
X02555Y00802*
X02917Y0082D02*
D01*
X02917Y00822*
X02916Y00825*
X02916Y00827*
X02916Y00829*
X02915Y00832*
X02914Y00834*
X02913Y00836*
X02912Y00838*
X0291Y0084*
X02909Y00842*
X02907Y00844*
X02907Y00844*
D01*
X02905Y00846*
X02903Y00847*
X02901Y00849*
X02899Y0085*
X02897Y00851*
X02894Y00852*
X02892Y00853*
X0289Y00854*
X02887Y00854*
X02885Y00855*
X02882Y00855*
X02881Y00855*
X02781Y00887D02*
D01*
X02787Y00882*
X02793Y00877*
X02799Y00873*
X02806Y00869*
X02813Y00865*
X0282Y00862*
X02827Y00859*
X02835Y00857*
X02842Y00856*
X0285Y00855*
X02858Y00855*
X0286Y00855*
X02748Y0094D02*
D01*
X02748Y00937*
X02748Y00934*
X02749Y0093*
X0275Y00927*
X02751Y00924*
X02752Y00921*
X02754Y00918*
X02755Y00915*
X02757Y00912*
X02759Y0091*
X02761Y00907*
X02762Y00907*
X02748Y00956D02*
D01*
X02748Y00958*
X02748Y0096*
X02747Y00962*
X02747Y00964*
X02746Y00965*
X02745Y00967*
X02745Y00969*
X02744Y00971*
X02743Y00972*
X02741Y00974*
X0274Y00975*
X0274Y00976*
X02426Y00275D02*
D01*
X02426Y00275*
X02426Y00276*
X02426Y00276*
X02426Y00276*
X02426Y00277*
X02425Y00277*
X02425Y00277*
X02425Y00278*
X02425Y00278*
X02424Y00278*
X02424Y00278*
X02424Y00278*
X02424Y00279*
X02423Y00279*
X02423Y00279*
X02423Y00279*
X02422Y00279*
X02422Y00279*
X02422Y00279*
X02421Y00279*
X02608Y00861D02*
D01*
X02614Y00866*
X02618Y00872*
X02623Y00879*
X02627Y00885*
X0263Y00892*
X02633Y00899*
X02636Y00907*
X02638Y00914*
X02639Y00922*
X0264Y00929*
X02641Y00937*
X02641Y00939*
X02649Y00976D02*
D01*
X02648Y00974*
X02647Y00973*
X02645Y00971*
X02644Y00969*
X02643Y00968*
X02643Y00966*
X02642Y00964*
X02642Y00962*
X02641Y0096*
X02641Y00958*
X02641Y00956*
X02641Y00956*
X02601Y00868D02*
D01*
X02605Y00873*
X0261Y00879*
X02614Y00884*
X02617Y0089*
X0262Y00897*
X02623Y00903*
X02625Y0091*
X02627Y00916*
X02629Y00923*
X02629Y0093*
X0263Y00937*
X0263Y00939*
Y00956D02*
D01*
X0263Y00958*
X0263Y0096*
X02629Y00962*
X02629Y00964*
X02628Y00965*
X02627Y00967*
X02627Y00969*
X02626Y00971*
X02624Y00972*
X02623Y00974*
X02622Y00975*
X02622Y00976*
X02584Y00305D02*
X02587Y0032D01*
X02577Y00297D02*
D01*
X0259Y00327D02*
Y00404D01*
X02596Y00275D02*
X02596Y00275D01*
X02604Y00279D02*
X0261D01*
X026Y00278D02*
D01*
X02602Y00389D02*
D01*
Y00387D02*
Y00389D01*
Y00376D02*
Y00387D01*
X02609Y00369D02*
X02616D01*
X02607Y00354D02*
X02616D01*
X02607Y00339D02*
X02619D01*
X02604Y00324D02*
X02619D01*
X02597Y00318D02*
D01*
X02592Y00297D02*
X02597Y00318D01*
X02602Y00389D02*
Y00396D01*
X0259Y00404D02*
D01*
X02608Y00457D02*
D01*
X02923Y00398D02*
X02926Y004D01*
X0291Y00384D02*
X02923Y00398D01*
X02909Y00381D02*
X0291Y00384D01*
X02909Y00366D02*
Y00381D01*
X02916Y00359D02*
D01*
X02903Y00344D02*
X02916D01*
X02903Y00329D02*
X02915D01*
X02905Y00314D02*
X02915D01*
X02897Y00291D02*
Y00306D01*
Y00291D02*
Y00289D01*
X02926Y004D02*
X02926Y004D01*
X02928Y00404D02*
Y00834D01*
X02923Y00275D02*
D01*
X02911Y004D02*
X02911Y004D01*
X02912Y00402D02*
D01*
X02917Y00419D02*
Y0082D01*
Y00419D02*
Y00419D01*
X02915Y00852D02*
X02925Y00842D01*
X02899Y00285D02*
D01*
X02767Y00976D02*
Y00976D01*
X02759Y0094D02*
Y00956D01*
X0277Y00914D02*
X02789Y00895D01*
X0286Y00866D02*
X02881D01*
X02899Y00285D02*
X02905Y00279D01*
X02885Y00352D02*
Y00352D01*
Y00276D02*
Y00352D01*
X02748Y00282D02*
D01*
X02748Y00285D02*
D01*
X02737Y00267D02*
X02737Y00267D01*
X02748Y00285D02*
Y00289D01*
X02737Y00387D02*
X02787Y00437D01*
X02748Y00377D02*
Y0038D01*
X02748Y00355D02*
X02748Y00377D01*
X02748Y00355D02*
D01*
X02733Y00348D02*
X0274D01*
X02733Y00333D02*
X0275D01*
X02733Y00318D02*
X0275D01*
X02733Y00303D02*
X0274D01*
X02748Y00295D02*
D01*
Y00291D02*
Y00295D01*
X02748Y00289D02*
X02748Y00291D01*
X02748Y0038D02*
D01*
X02749Y00383D02*
X02795Y00429D01*
X02633Y00472D02*
X02652Y0049D01*
X02633Y00472D02*
D01*
X02526Y0036D02*
X02543Y00378D01*
X02515Y0036D02*
D01*
D01*
X02504Y0035D02*
D01*
X02491Y00341D02*
X02494Y00339D01*
X02481Y00331D02*
X02483Y00328D01*
X02469Y00321D02*
X02473Y00318D01*
X02459Y0031D02*
X02462Y00307D01*
X0246Y00295D02*
X02462Y00297D01*
X02543Y00378D02*
X02553Y00388D01*
X02444Y00279D02*
X0246Y00295D01*
X02807Y00485D02*
Y00775D01*
X02818Y00485D02*
Y00775D01*
X02673Y00569D02*
Y00775D01*
X02684Y00569D02*
Y00775D01*
X02555Y00393D02*
Y00802D01*
X02692Y00795D02*
Y00795D01*
X02665Y00795D02*
Y00795D01*
X02625Y0048D02*
X02644Y00498D01*
X02464Y00285D02*
X02563Y00383D01*
X02566Y0039D02*
Y00802D01*
X02771Y00279D02*
X02779D01*
X02799Y00795D02*
Y00795D01*
X02826Y00795D02*
Y00795D01*
X02578Y0083D02*
X02608Y00861D01*
X02463Y00281D02*
D01*
X02578Y0083D02*
D01*
X02555Y00393D02*
D01*
X02928Y00279D02*
X02937D01*
X02881Y00855D02*
D01*
X0286D02*
X02881D01*
X02748Y0094D02*
Y00956D01*
X0274Y00976D02*
Y00976D01*
X02762Y00907D02*
X02781Y00887D01*
X02421Y00279D02*
D01*
X02413D02*
X02421D01*
X02641Y00939D02*
Y00956D01*
X02649Y00976D02*
Y00976D01*
Y00976D02*
D01*
X0257Y00838D02*
X02601Y00868D01*
X0263Y00939D02*
Y00956D01*
X02622Y00976D02*
Y00976D01*
G54D153*
X01849Y03701D02*
X06294D01*
X01909Y04284D02*
X01941Y04316D01*
X01496Y04204D02*
X01576Y04284D01*
X01909*
X02152Y04316D02*
X02186Y04283D01*
X01941Y04316D02*
X02152D01*
X02186Y04283D02*
X0257D01*
X01413Y04204D02*
X01496D01*
X01362Y04256D02*
X01413Y04204D01*
X01294Y04256D02*
X01362D01*
G54D160*
X0418Y02595D03*
X04298D03*
G54D167*
X02043Y04157D03*
G54D171*
X02494Y02661D03*
X0261Y00279D03*
X02578D03*
X02748Y00282D03*
X02905Y00279D03*
X02692Y00795D03*
X02665D03*
X02779Y00279D03*
X02937D03*
X0274Y00976D03*
X02767D03*
X02413Y00279D03*
X02444D03*
X02649Y00976D03*
X02622D03*
X02799Y00795D03*
X02826D03*
X0233Y02215D03*
X01798Y01304D03*
X03379Y01386D03*
X02821Y02601D03*
X03554Y01891D03*
X02841Y02263D03*
X02394Y0272D03*
X01567Y01285D03*
X02494Y02696D03*
X03404Y01363D03*
X02803Y02307D03*
X01822Y01674D03*
X01893Y01693D03*
X02409Y02314D03*
X02958Y02621D03*
X03804Y0184D03*
X01879Y01811D03*
X03407Y01411D03*
X02575Y02412D03*
X02499Y02236D03*
X02948Y02456D03*
X03719Y01766D03*
X02645Y02274D03*
X03379Y01336D03*
X01393Y01816D03*
X04794Y02808D03*
X03183Y03135D03*
X03277Y02963D03*
X03197Y0297D03*
X03188Y03187D03*
X0323Y03235D03*
X03275Y03141D03*
X03056Y01811D03*
X02434Y03546D03*
X02591Y03186D03*
X0259Y03288D03*
X00996Y02256D03*
X02004Y01336D03*
X02028Y01361D03*
X02549Y01755D03*
X02418Y03118D03*
X02414Y03199D03*
X02462Y03172D03*
X01408Y0398D03*
X00996Y01187D03*
X00988Y01717D03*
X02353Y04017D03*
X04039Y02406D03*
X04134Y01651D03*
X03994Y01551D03*
X04134Y01751D03*
X04151Y01623D03*
X03969Y01552D03*
X03944Y01816D03*
X04179Y01601D03*
X04034Y01546D03*
X04064Y01796D03*
Y01511D03*
X03263Y03303D03*
X01569Y04171D03*
X05267Y04088D03*
X05577Y02214D03*
X02694Y01481D03*
X02384Y01941D03*
X06334Y03266D03*
X03744Y03261D03*
X05634Y02236D03*
X02626Y0177D03*
X06304Y03121D03*
X03939D03*
X02604Y01734D03*
X02299Y01916D03*
X02579Y0179D03*
X02259Y03261D03*
X03374Y03273D03*
X06282Y03226D03*
X03806Y03235D03*
X0337Y02888D03*
X0257Y04283D03*
X01459Y03147D03*
X0144Y03557D03*
X01903Y04018D03*
X03623Y02587D03*
X03542Y03319D03*
X03653Y03293D03*
X03394Y03447D03*
X03436Y03457D03*
X02799Y03616D03*
X03589Y01711D03*
X02478Y00937D03*
X02206Y01298D03*
X02205Y032D03*
X02502Y01316D03*
X02525Y02463D03*
X03342Y02263D03*
X03498Y02341D03*
X02429Y02621D03*
X01004Y00906D03*
X02446Y01437D03*
X01008Y0143D03*
X02409Y01967D03*
X01009Y01956D03*
X0102Y02481D03*
X02643Y01616D03*
X02666Y0164D03*
X01884Y03601D03*
X01754Y03661D03*
X03424Y03636D03*
X01549Y03621D03*
X03239Y03596D03*
X01574D03*
X02083Y01411D03*
X02059Y01386D03*
X01294Y04256D03*
X02234Y03506D03*
X03529Y03481D03*
X02679Y03661D03*
X02993Y03751D03*
X03699D03*
X03014Y03831D03*
X03699Y03836D03*
X02894Y01561D03*
X02919Y01536D03*
X02274Y01506D03*
X02719Y01591D03*
X03724Y01675D03*
X06309Y03199D03*
X06339Y03151D03*
X04754Y04115D03*
X01779Y04156D03*
X03504Y04086D03*
X03854Y03151D03*
X03829Y03176D03*
X03799Y03201D03*
X06439Y03191D03*
X06354Y03331D03*
X06444Y03291D03*
X03302Y03344D03*
X06409Y03371D03*
X06447Y03396D03*
X06479Y03426D03*
X06509Y03456D03*
X03469D03*
X01849Y03701D03*
X06294D03*
M02*